(kicad_pcb
	(version 20241229)
	(generator "pcbnew")
	(generator_version "9.0")
	(general
		(thickness 1.61)
		(legacy_teardrops no)
	)
	(paper "A3")
	(title_block
		(title "RDIMM DDR5 Tester")
		(date "2026-05-21")
		(rev "2.2.0")
		(company "Antmicro")
		(comment 9 "footprints 703-707 of 796")
	)
	(layers
		(0 "F.Cu" signal)
		(4 "In1.Cu" power)
		(6 "In2.Cu" mixed)
		(8 "In3.Cu" power)
		(10 "In4.Cu" mixed)
		(12 "In5.Cu" power)
		(14 "In6.Cu" mixed)
		(16 "In7.Cu" power)
		(18 "In8.Cu" power)
		(20 "In9.Cu" mixed)
		(22 "In10.Cu" power)
		(2 "B.Cu" signal)
		(9 "F.Adhes" user "F.Adhesive")
		(11 "B.Adhes" user "B.Adhesive")
		(13 "F.Paste" user)
		(15 "B.Paste" user)
		(5 "F.SilkS" user "F.Silkscreen")
		(7 "B.SilkS" user "B.Silkscreen")
		(1 "F.Mask" user)
		(3 "B.Mask" user)
		(17 "Dwgs.User" user "User.Drawings")
		(19 "Cmts.User" user "User.Comments")
		(21 "Eco1.User" user "User.Eco1")
		(23 "Eco2.User" user "User.Eco2")
		(25 "Edge.Cuts" user)
		(27 "Margin" user)
		(31 "F.CrtYd" user "F.Courtyard")
		(29 "B.CrtYd" user "B.Courtyard")
		(35 "F.Fab" user)
		(33 "B.Fab" user)
	)
	(footprint "antmicro-footprints:R_0402_1005Metric"
		(layer "B.Cu")
		(at 245.1 183.149 90)
		(descr "Resistor SMD 0402")
		(tags "resistor SMD 0402")
		(property "Reference" "R223"
			(at 1 0.35 90)
			(layer "B.SilkS")
			(effects
				(font
					(size 0.7 0.7)
					(thickness 0.15)
				)
				(justify right bottom mirror)
			)
		)
		(property "Value" "R_47k_0402"
			(at -1.011843 -1.772047 90)
			(layer "B.Fab")
			(effects
				(font
					(size 0.7 0.7)
					(thickness 0.15)
				)
				(justify right bottom mirror)
			)
		)
		(property "Datasheet" "https://www.bourns.com/docs/product-datasheets/cr.pdf"
			(at 0 0 90)
			(layer "F.Fab")
			(hide yes)
			(effects
				(font
					(size 1.27 1.27)
					(thickness 0.15)
				)
			)
		)
		(property "MPN" "CR0402-FX-4702GLF"
			(at 0 0 90)
			(unlocked yes)
			(layer "B.Fab")
			(hide yes)
			(effects
				(font
					(size 1 1)
					(thickness 0.15)
				)
				(justify mirror)
			)
		)
		(property "Manufacturer" "Bourns"
			(at 0 0 90)
			(unlocked yes)
			(layer "B.Fab")
			(hide yes)
			(effects
				(font
					(size 1 1)
					(thickness 0.15)
				)
				(justify mirror)
			)
		)
		(property "License" "Apache-2.0"
			(at 0 0 90)
			(unlocked yes)
			(layer "B.Fab")
			(hide yes)
			(effects
				(font
					(size 1 1)
					(thickness 0.15)
				)
				(justify mirror)
			)
		)
		(property "Author" "Antmicro"
			(at 0 0 90)
			(unlocked yes)
			(layer "B.Fab")
			(hide yes)
			(effects
				(font
					(size 1 1)
					(thickness 0.15)
				)
				(justify mirror)
			)
		)
		(property "Val" "47k"
			(at 0 0 90)
			(unlocked yes)
			(layer "B.Fab")
			(hide yes)
			(effects
				(font
					(size 1 1)
					(thickness 0.15)
				)
				(justify mirror)
			)
		)
		(property "Tolerance" "1%"
			(at 0 0 90)
			(unlocked yes)
			(layer "B.Fab")
			(hide yes)
			(effects
				(font
					(size 1 1)
					(thickness 0.15)
				)
				(justify mirror)
			)
		)
		(sheetname "/I^{2}C + I3C/")
		(sheetfile "i2c.kicad_sch")
		(attr smd)
		(fp_rect
			(start -0.925 0.47)
			(end 0.925 -0.47)
			(stroke
				(width 0.05)
				(type default)
			)
			(fill no)
			(layer "B.CrtYd")
		)
		(fp_rect
			(start -0.5 0.25)
			(end 0.5 -0.25)
			(stroke
				(width 0.15)
				(type solid)
			)
			(fill no)
			(layer "B.Fab")
		)
		(fp_text user "${REFERENCE}"
			(at -0.95 -3.168 270)
			(layer "B.Fab")
			(effects
				(font
					(size 0.7 0.7)
					(thickness 0.15)
				)
				(justify left bottom mirror)
			)
		)
		(fp_text user "Author: Antmicro"
			(at -0.95 -4.169 270)
			(layer "B.Fab")
			(effects
				(font
					(size 0.7 0.7)
					(thickness 0.15)
				)
				(justify left bottom mirror)
			)
		)
		(fp_text user "License: Apache-2.0"
			(at -0.95 -5.169 270)
			(layer "B.Fab")
			(effects
				(font
					(size 0.7 0.7)
					(thickness 0.15)
				)
				(justify left bottom mirror)
			)
		)
		(pad "1" smd roundrect
			(at -0.48 0 90)
			(size 0.59 0.64)
			(layers "B.Cu" "B.Mask" "B.Paste")
			(roundrect_rratio 0.25)
			(net 778 "~{FPGA_I3C_EXT_PU}")
			(pintype "passive")
		)
		(pad "2" smd roundrect
			(at 0.48 0 90)
			(size 0.59 0.64)
			(layers "B.Cu" "B.Mask" "B.Paste")
			(roundrect_rratio 0.25)
			(net 151 "+3V3")
			(pintype "passive")
		)
	)
	(footprint "antmicro-footprints:R_0402_1005Metric"
		(layer "B.Cu")
		(at 237.925 157.605 -90)
		(descr "Resistor SMD 0402")
		(tags "resistor SMD 0402")
		(property "Reference" "R212"
			(at 0.875 -0.485 90)
			(layer "B.SilkS")
			(effects
				(font
					(size 0.7 0.7)
					(thickness 0.15)
				)
				(justify left bottom mirror)
			)
		)
		(property "Value" "R_0R_0402"
			(at -1.011843 -1.772047 90)
			(layer "B.Fab")
			(effects
				(font
					(size 0.7 0.7)
					(thickness 0.15)
				)
				(justify left bottom mirror)
			)
		)
		(property "Datasheet" "https://industrial.panasonic.com/cdbs/www-data/pdf/RDA0000/AOA0000C301.pdf"
			(at 0 0 270)
			(layer "F.Fab")
			(hide yes)
			(effects
				(font
					(size 1.27 1.27)
					(thickness 0.15)
				)
			)
		)
		(property "MPN" "ERJ2GE0R00X"
			(at 0 0 270)
			(unlocked yes)
			(layer "B.Fab")
			(hide yes)
			(effects
				(font
					(size 1 1)
					(thickness 0.15)
				)
				(justify mirror)
			)
		)
		(property "Manufacturer" "Panasonic"
			(at 0 0 270)
			(unlocked yes)
			(layer "B.Fab")
			(hide yes)
			(effects
				(font
					(size 1 1)
					(thickness 0.15)
				)
				(justify mirror)
			)
		)
		(property "License" "Apache-2.0"
			(at 0 0 270)
			(unlocked yes)
			(layer "B.Fab")
			(hide yes)
			(effects
				(font
					(size 1 1)
					(thickness 0.15)
				)
				(justify mirror)
			)
		)
		(property "Author" "Antmicro"
			(at 0 0 270)
			(unlocked yes)
			(layer "B.Fab")
			(hide yes)
			(effects
				(font
					(size 1 1)
					(thickness 0.15)
				)
				(justify mirror)
			)
		)
		(property "Val" "0R"
			(at 0 0 270)
			(unlocked yes)
			(layer "B.Fab")
			(hide yes)
			(effects
				(font
					(size 1 1)
					(thickness 0.15)
				)
				(justify mirror)
			)
		)
		(property "Tolerance" "~"
			(at 0 0 270)
			(unlocked yes)
			(layer "B.Fab")
			(hide yes)
			(effects
				(font
					(size 1 1)
					(thickness 0.15)
				)
				(justify mirror)
			)
		)
		(property "Current" "1A"
			(at 0 0 270)
			(unlocked yes)
			(layer "B.Fab")
			(hide yes)
			(effects
				(font
					(size 1 1)
					(thickness 0.15)
				)
				(justify mirror)
			)
		)
		(sheetname "/Supply/DC-DC IO/")
		(sheetfile "dc-dc-io.kicad_sch")
		(attr smd)
		(fp_rect
			(start -0.925 0.47)
			(end 0.925 -0.47)
			(stroke
				(width 0.05)
				(type default)
			)
			(fill no)
			(layer "B.CrtYd")
		)
		(fp_rect
			(start -0.5 0.25)
			(end 0.5 -0.25)
			(stroke
				(width 0.15)
				(type solid)
			)
			(fill no)
			(layer "B.Fab")
		)
		(fp_text user "${REFERENCE}"
			(at -0.95 -3.168 90)
			(layer "B.Fab")
			(effects
				(font
					(size 0.7 0.7)
					(thickness 0.15)
				)
				(justify left bottom mirror)
			)
		)
		(fp_text user "License: Apache-2.0"
			(at -0.95 -5.169 90)
			(layer "B.Fab")
			(effects
				(font
					(size 0.7 0.7)
					(thickness 0.15)
				)
				(justify left bottom mirror)
			)
		)
		(fp_text user "Author: Antmicro"
			(at -0.95 -4.169 90)
			(layer "B.Fab")
			(effects
				(font
					(size 0.7 0.7)
					(thickness 0.15)
				)
				(justify left bottom mirror)
			)
		)
		(pad "1" smd roundrect
			(at -0.48 0 270)
			(size 0.59 0.64)
			(layers "B.Cu" "B.Mask" "B.Paste")
			(roundrect_rratio 0.25)
			(net 732 "Net-(U28-IN2+)")
			(pintype "passive")
		)
		(pad "2" smd roundrect
			(at 0.48 0 270)
			(size 0.59 0.64)
			(layers "B.Cu" "B.Mask" "B.Paste")
			(roundrect_rratio 0.25)
			(net 686 "/Supply/DC-DC IO/5V_SEN_+")
			(pintype "passive")
		)
	)
	(footprint "antmicro-footprints:C_0402_1005Metric"
		(layer "B.Cu")
		(at 169.385 158.45 180)
		(descr "Capacitor SMD 0402")
		(tags "capacitor SMD 0402")
		(property "Reference" "C164"
			(at 1.285 -0.45 0)
			(layer "B.SilkS")
			(effects
				(font
					(size 0.7 0.7)
					(thickness 0.15)
				)
				(justify left bottom mirror)
			)
		)
		(property "Value" "C_100n_0402"
			(at -1.022927 -2.155213 0)
			(layer "B.Fab")
			(effects
				(font
					(size 0.7 0.7)
					(thickness 0.15)
				)
				(justify left bottom mirror)
			)
		)
		(property "Datasheet" "https://www.murata.com/products/productdetail?partno=GRM155R61H104KE14%23"
			(at 0 0 180)
			(layer "F.Fab")
			(hide yes)
			(effects
				(font
					(size 1.27 1.27)
					(thickness 0.15)
				)
			)
		)
		(property "MPN" "GRM155R61H104KE14D"
			(at 0 0 180)
			(unlocked yes)
			(layer "B.Fab")
			(hide yes)
			(effects
				(font
					(size 1 1)
					(thickness 0.15)
				)
				(justify mirror)
			)
		)
		(property "Manufacturer" "Murata"
			(at 0 0 180)
			(unlocked yes)
			(layer "B.Fab")
			(hide yes)
			(effects
				(font
					(size 1 1)
					(thickness 0.15)
				)
				(justify mirror)
			)
		)
		(property "License" "Apache-2.0"
			(at 0 0 180)
			(unlocked yes)
			(layer "B.Fab")
			(hide yes)
			(effects
				(font
					(size 1 1)
					(thickness 0.15)
				)
				(justify mirror)
			)
		)
		(property "Author" "Antmicro"
			(at 0 0 180)
			(unlocked yes)
			(layer "B.Fab")
			(hide yes)
			(effects
				(font
					(size 1 1)
					(thickness 0.15)
				)
				(justify mirror)
			)
		)
		(property "Val" "100n"
			(at 0 0 180)
			(unlocked yes)
			(layer "B.Fab")
			(hide yes)
			(effects
				(font
					(size 1 1)
					(thickness 0.15)
				)
				(justify mirror)
			)
		)
		(property "Voltage" "50V"
			(at 0 0 180)
			(unlocked yes)
			(layer "B.Fab")
			(hide yes)
			(effects
				(font
					(size 1 1)
					(thickness 0.15)
				)
				(justify mirror)
			)
		)
		(property "Dielectric" "X5R"
			(at 0 0 180)
			(unlocked yes)
			(layer "B.Fab")
			(hide yes)
			(effects
				(font
					(size 1 1)
					(thickness 0.15)
				)
				(justify mirror)
			)
		)
		(sheetname "/FPGA banks HP/")
		(sheetfile "fpga-hp-banks.kicad_sch")
		(attr smd)
		(fp_rect
			(start -0.925 0.47)
			(end 0.925 -0.47)
			(stroke
				(width 0.05)
				(type default)
			)
			(fill no)
			(layer "B.CrtYd")
		)
		(fp_line
			(start 0.504 0.25)
			(end 0.504 -0.248)
			(stroke
				(width 0.15)
				(type solid)
			)
			(layer "B.Fab")
		)
		(fp_line
			(start 0.504 -0.248)
			(end -0.494 -0.248)
			(stroke
				(width 0.15)
				(type solid)
			)
			(layer "B.Fab")
		)
		(fp_line
			(start -0.494 0.25)
			(end 0.504 0.25)
			(stroke
				(width 0.15)
				(type solid)
			)
			(layer "B.Fab")
		)
		(fp_line
			(start -0.494 -0.248)
			(end -0.494 0.25)
			(stroke
				(width 0.15)
				(type solid)
			)
			(layer "B.Fab")
		)
		(fp_text user "License: Apache-2.0"
			(at -0.939 -5.799 0)
			(layer "B.Fab")
			(effects
				(font
					(size 0.7 0.7)
					(thickness 0.15)
				)
				(justify left bottom mirror)
			)
		)
		(fp_text user "${REFERENCE}"
			(at -0.939 -4.599 0)
			(layer "B.Fab")
			(effects
				(font
					(size 0.7 0.7)
					(thickness 0.15)
				)
				(justify left bottom mirror)
			)
		)
		(fp_text user "Author: Antmicro"
			(at -0.939 -3.399 0)
			(layer "B.Fab")
			(effects
				(font
					(size 0.7 0.7)
					(thickness 0.15)
				)
				(justify left bottom mirror)
			)
		)
		(pad "1" smd roundrect
			(at -0.48 0 180)
			(size 0.59 0.64)
			(layers "B.Cu" "B.Mask" "B.Paste")
			(roundrect_rratio 0.25)
			(net 1 "GND")
			(pintype "passive")
		)
		(pad "2" smd roundrect
			(at 0.48 0 180)
			(size 0.59 0.64)
			(layers "B.Cu" "B.Mask" "B.Paste")
			(roundrect_rratio 0.25)
			(net 151 "+3V3")
			(pintype "passive")
		)
	)
	(footprint "antmicro-footprints:C_0402_1005Metric_EIA"
		(layer "B.Cu")
		(at 182 159.5 -90)
		(descr "Capacitor SMD 0402 (1005 Metric), square (rectangular) end terminal, IPC_7351 nominal, (Body size source: IPC-SM-782 page 76, https://www.pcb-3d.com/wordpress/wp-content/uploads/ipc-sm-782a_amendment_1_and_2.pdf)")
		(tags "capacitor 0402")
		(property "Reference" "C70"
			(at 0 -1.5 90)
			(layer "B.SilkS")
			(effects
				(font
					(size 0.7 0.7)
					(thickness 0.15)
				)
				(justify left bottom mirror)
			)
		)
		(property "Value" "C_10u_10V_0402"
			(at 0 -1.169 90)
			(layer "B.Fab")
			(effects
				(font
					(size 0.7 0.7)
					(thickness 0.15)
				)
				(justify left bottom mirror)
			)
		)
		(property "Datasheet" "https://www.murata.com/products/productdetail?partno=GRM155R61A106ME11%23"
			(at 0 0 270)
			(layer "F.Fab")
			(hide yes)
			(effects
				(font
					(size 1.27 1.27)
					(thickness 0.15)
				)
			)
		)
		(property "MPN" "GRM155R61A106ME11D"
			(at 0 0 270)
			(unlocked yes)
			(layer "B.Fab")
			(hide yes)
			(effects
				(font
					(size 1 1)
					(thickness 0.15)
				)
				(justify mirror)
			)
		)
		(property "Manufacturer" "Murata"
			(at 0 0 270)
			(unlocked yes)
			(layer "B.Fab")
			(hide yes)
			(effects
				(font
					(size 1 1)
					(thickness 0.15)
				)
				(justify mirror)
			)
		)
		(property "License" "Apache-2.0"
			(at 0 0 270)
			(unlocked yes)
			(layer "B.Fab")
			(hide yes)
			(effects
				(font
					(size 1 1)
					(thickness 0.15)
				)
				(justify mirror)
			)
		)
		(property "Author" "Antmicro"
			(at 0 0 270)
			(unlocked yes)
			(layer "B.Fab")
			(hide yes)
			(effects
				(font
					(size 1 1)
					(thickness 0.15)
				)
				(justify mirror)
			)
		)
		(property "Val" "10u"
			(at 0 0 270)
			(unlocked yes)
			(layer "B.Fab")
			(hide yes)
			(effects
				(font
					(size 1 1)
					(thickness 0.15)
				)
				(justify mirror)
			)
		)
		(property "Voltage" "10V"
			(at 0 0 270)
			(unlocked yes)
			(layer "B.Fab")
			(hide yes)
			(effects
				(font
					(size 1 1)
					(thickness 0.15)
				)
				(justify mirror)
			)
		)
		(property "Dielectric" "X5R"
			(at 0 0 270)
			(unlocked yes)
			(layer "B.Fab")
			(hide yes)
			(effects
				(font
					(size 1 1)
					(thickness 0.15)
				)
				(justify mirror)
			)
		)
		(sheetname "/FPGA power/")
		(sheetfile "fpga-power.kicad_sch")
		(attr smd)
		(fp_rect
			(start -0.95 0.45)
			(end 0.95 -0.45)
			(stroke
				(width 0.05)
				(type default)
			)
			(fill no)
			(layer "B.CrtYd")
		)
		(fp_line
			(start -0.5 0.25)
			(end 0.498 0.25)
			(stroke
				(width 0.15)
				(type solid)
			)
			(layer "B.Fab")
		)
		(fp_line
			(start 0.498 0.25)
			(end 0.498 -0.248)
			(stroke
				(width 0.15)
				(type solid)
			)
			(layer "B.Fab")
		)
		(fp_line
			(start -0.5 -0.248)
			(end -0.5 0.25)
			(stroke
				(width 0.15)
				(type solid)
			)
			(layer "B.Fab")
		)
		(fp_line
			(start 0.498 -0.248)
			(end -0.5 -0.248)
			(stroke
				(width 0.15)
				(type solid)
			)
			(layer "B.Fab")
		)
		(fp_text user "Author: Antmicro"
			(at -0.9656 -5.569 90)
			(layer "B.Fab")
			(effects
				(font
					(size 0.7 0.7)
					(thickness 0.15)
				)
				(justify left bottom mirror)
			)
		)
		(fp_text user "License: Apache-2.0"
			(at -0.9656 -4.369 90)
			(layer "B.Fab")
			(effects
				(font
					(size 0.7 0.7)
					(thickness 0.15)
				)
				(justify left bottom mirror)
			)
		)
		(fp_text user "${REFERENCE}"
			(at -0.9656 -3.169 90)
			(layer "B.Fab")
			(effects
				(font
					(size 0.7 0.7)
					(thickness 0.15)
				)
				(justify left bottom mirror)
			)
		)
		(pad "1" smd roundrect
			(at -0.5 0 180)
			(size 0.6 0.6)
			(layers "B.Cu" "B.Mask" "B.Paste")
			(roundrect_rratio 0.25)
			(net 1 "GND")
			(pintype "passive")
		)
		(pad "2" smd roundrect
			(at 0.498 0 270)
			(size 0.6 0.6)
			(layers "B.Cu" "B.Mask" "B.Paste")
			(roundrect_rratio 0.25)
			(net 172 "+1V2_MGTAVTT")
			(pintype "passive")
		)
	)
	(footprint "antmicro-footprints:C_0402_1005Metric_EIA"
		(layer "B.Cu")
		(at 189 162.498 90)
		(descr "Capacitor SMD 0402 (1005 Metric), square (rectangular) end terminal, IPC_7351 nominal, (Body size source: IPC-SM-782 page 76, https://www.pcb-3d.com/wordpress/wp-content/uploads/ipc-sm-782a_amendment_1_and_2.pdf)")
		(tags "capacitor 0402")
		(property "Reference" "C167"
			(at -3.952 0.25 90)
			(layer "B.SilkS")
			(effects
				(font
					(size 0.7 0.7)
					(thickness 0.15)
				)
				(justify right bottom mirror)
			)
		)
		(property "Value" "C_10u_10V_0402"
			(at 0 -1.169 90)
			(layer "B.Fab")
			(effects
				(font
					(size 0.7 0.7)
					(thickness 0.15)
				)
				(justify right bottom mirror)
			)
		)
		(property "Datasheet" "https://www.murata.com/products/productdetail?partno=GRM155R61A106ME11%23"
			(at 0 0 90)
			(layer "F.Fab")
			(hide yes)
			(effects
				(font
					(size 1.27 1.27)
					(thickness 0.15)
				)
			)
		)
		(property "MPN" "GRM155R61A106ME11D"
			(at 0 0 90)
			(unlocked yes)
			(layer "B.Fab")
			(hide yes)
			(effects
				(font
					(size 1 1)
					(thickness 0.15)
				)
				(justify mirror)
			)
		)
		(property "Manufacturer" "Murata"
			(at 0 0 90)
			(unlocked yes)
			(layer "B.Fab")
			(hide yes)
			(effects
				(font
					(size 1 1)
					(thickness 0.15)
				)
				(justify mirror)
			)
		)
		(property "License" "Apache-2.0"
			(at 0 0 90)
			(unlocked yes)
			(layer "B.Fab")
			(hide yes)
			(effects
				(font
					(size 1 1)
					(thickness 0.15)
				)
				(justify mirror)
			)
		)
		(property "Author" "Antmicro"
			(at 0 0 90)
			(unlocked yes)
			(layer "B.Fab")
			(hide yes)
			(effects
				(font
					(size 1 1)
					(thickness 0.15)
				)
				(justify mirror)
			)
		)
		(property "Val" "10u"
			(at 0 0 90)
			(unlocked yes)
			(layer "B.Fab")
			(hide yes)
			(effects
				(font
					(size 1 1)
					(thickness 0.15)
				)
				(justify mirror)
			)
		)
		(property "Voltage" "10V"
			(at 0 0 90)
			(unlocked yes)
			(layer "B.Fab")
			(hide yes)
			(effects
				(font
					(size 1 1)
					(thickness 0.15)
				)
				(justify mirror)
			)
		)
		(property "Dielectric" "X5R"
			(at 0 0 90)
			(unlocked yes)
			(layer "B.Fab")
			(hide yes)
			(effects
				(font
					(size 1 1)
					(thickness 0.15)
				)
				(justify mirror)
			)
		)
		(sheetname "/FPGA power/")
		(sheetfile "fpga-power.kicad_sch")
		(attr smd)
		(fp_rect
			(start -0.95 0.45)
			(end 0.95 -0.45)
			(stroke
				(width 0.05)
				(type default)
			)
			(fill no)
			(layer "B.CrtYd")
		)
		(fp_line
			(start 0.498 -0.248)
			(end -0.5 -0.248)
			(stroke
				(width 0.15)
				(type solid)
			)
			(layer "B.Fab")
		)
		(fp_line
			(start -0.5 -0.248)
			(end -0.5 0.25)
			(stroke
				(width 0.15)
				(type solid)
			)
			(layer "B.Fab")
		)
		(fp_line
			(start 0.498 0.25)
			(end 0.498 -0.248)
			(stroke
				(width 0.15)
				(type solid)
			)
			(layer "B.Fab")
		)
		(fp_line
			(start -0.5 0.25)
			(end 0.498 0.25)
			(stroke
				(width 0.15)
				(type solid)
			)
			(layer "B.Fab")
		)
		(fp_text user "Author: Antmicro"
			(at -0.9656 -5.569 270)
			(layer "B.Fab")
			(effects
				(font
					(size 0.7 0.7)
					(thickness 0.15)
				)
				(justify left bottom mirror)
			)
		)
		(fp_text user "${REFERENCE}"
			(at -0.9656 -3.169 270)
			(layer "B.Fab")
			(effects
				(font
					(size 0.7 0.7)
					(thickness 0.15)
				)
				(justify left bottom mirror)
			)
		)
		(fp_text user "License: Apache-2.0"
			(at -0.9656 -4.369 270)
			(layer "B.Fab")
			(effects
				(font
					(size 0.7 0.7)
					(thickness 0.15)
				)
				(justify left bottom mirror)
			)
		)
		(pad "1" smd roundrect
			(at -0.5 0)
			(size 0.6 0.6)
			(layers "B.Cu" "B.Mask" "B.Paste")
			(roundrect_rratio 0.25)
			(net 1 "GND")
			(pintype "passive")
		)
		(pad "2" smd roundrect
			(at 0.498 0 90)
			(size 0.6 0.6)
			(layers "B.Cu" "B.Mask" "B.Paste")
			(roundrect_rratio 0.25)
			(net 172 "+1V2_MGTAVTT")
			(pintype "passive")
		)
	)
)
